# S9S_MB_2U (Grand Teton) — schematic netlist excerpt (pin names and nets, part order shuffled) for the footprints in the layout excerpt that follows; sources: Cadence DE-HDL packaged netlist, KiCad conversion of 03242023_DA0F0TMBIJ0_F0T_Motherboard_J_brd_V01_OCP.brd

J23  SCONN288_ADR50017P130CC  SCONN288_ADR50017-P130CC IO  pkg DDR288S_1-1VXB  page 104
  VIN_BULK0  = P12V_S3_AUX_CPU1_NVDIMM
  RFU0  = TP_CHD_CPU1_DIMM1_FRU_0
  VIN_MGMT  = P3V3_AUX
  HSCL  = I3C_SPD_DDRABCD_CPU1_LVC1_SCL_6
  HSDA  = I3C_SPD_DDRABCD_CPU1_LVC1_SDA
  VSS0  = GND
  DQ0_A  = M_D_CPU1_SA_DQ<0>
  VSS1  = GND
  DQ1_A  = M_D_CPU1_SA_DQ<1>
  VSS2  = GND
  DQS0_A_T  = M_D_CPU1_SA_DQS_DP<0>
  DQS0_A_C  = M_D_CPU1_SA_DQS_DN<0>
  VSS3  = GND
  DQ4_A  = M_D_CPU1_SA_DQ<4>
  VSS4  = GND
  DQ5_A  = M_D_CPU1_SA_DQ<5>
  VSS5  = GND
  DQ8_A  = M_D_CPU1_SA_DQ<8>
  VSS6  = GND
  DQ9_A  = M_D_CPU1_SA_DQ<9>
  VSS7  = GND
  DQS1_A_T  = M_D_CPU1_SA_DQS_DP<1>
  DQS1_A_C  = M_D_CPU1_SA_DQS_DN<1>
  VSS8  = GND
  DQ12_A  = M_D_CPU1_SA_DQ<12>
  VSS9  = GND
  DQ13_A  = M_D_CPU1_SA_DQ<13>
  VSS10  = GND
  DQ16_A  = M_D_CPU1_SA_DQ<16>
  VSS11  = GND
  DQ17_A  = M_D_CPU1_SA_DQ<17>
  VSS12  = GND
  DQS2_A_T  = M_D_CPU1_SA_DQS_DP<2>
  DQS2_A_C  = M_D_CPU1_SA_DQS_DN<2>
  VSS13  = GND
  DQ20_A  = M_D_CPU1_SA_DQ<20>
  VSS14  = GND
  DQ21_A  = M_D_CPU1_SA_DQ<21>
  VSS15  = GND
  DQ24_A  = M_D_CPU1_SA_DQ<24>
  VSS16  = GND
  DQ25_A  = M_D_CPU1_SA_DQ<25>
  VSS17  = GND
  DQS3_A_T  = M_D_CPU1_SA_DQS_DP<3>
  DQS3_A_C  = M_D_CPU1_SA_DQS_DN<3>
  VSS18  = GND
  DQ28_A  = M_D_CPU1_SA_DQ<28>
  VSS19  = GND
  DQ29_A  = M_D_CPU1_SA_DQ<29>
  VSS20  = GND
  CB0_A  = M_D_CPU1_SA_CB<0>
  VSS21  = GND
  CB1_A  = M_D_CPU1_SA_CB<1>
  VSS22  = GND
  DQS4_A_T  = M_D_CPU1_SA_DQS_DP<4>
  DQS4_A_C  = M_D_CPU1_SA_DQS_DN<4>
  VSS23  = GND
  CB4_A  = M_D_CPU1_SA_CB<4>
  VSS24  = GND
  CB5_A  = M_D_CPU1_SA_CB<5>
  VSS25  = GND
  ALERT_N  = M_D_CPU1_ALERT_N
  VSS26  = GND
  CS0_A_N  = M_D_CPU1_SA_CS_N<0>
  VSS27  = GND
  CA0_A  = M_D_CPU1_SA_CA<0>
  VSS28  = GND
  CA2_A  = M_D_CPU1_SA_CA<2>
  VSS29  = GND
  CA4_A  = M_D_CPU1_SA_CA<4>
  VSS30  = GND
  CA6_A  = M_D_CPU1_SA_CA<6>
  VSS31  = GND
  PAR_A  = M_D_CPU1_SA_PAR
  VSS32  = GND
  CA0_B  = M_D_CPU1_SB_CA<0>
  VSS33  = GND
  CA2_B  = M_D_CPU1_SB_CA<2>
  VSS34  = GND
  CA4_B  = M_D_CPU1_SB_CA<4>
  VSS35  = GND
  CA6_B  = M_D_CPU1_SB_CA<6>
  VSS36  = GND
  CS0_B_N  = M_D_CPU1_SB_CS_N<0>
  VSS37  = GND
  \lbd||rsp_a_n\  = M_D_CPU1_SA_RSP<0>
  \lbs||rsp_b_n\  = M_D_CPU1_SB_RSP<0>
  VSS38  = GND
  CB4_B  = M_D_CPU1_SB_CB<4>
  VSS39  = GND
  CB5_B  = M_D_CPU1_SB_CB<5>
  VSS40  = GND
  \dqs9_b_t||tdqs9_b_t||dbi4_b_n\  = M_D_CPU1_SB_DQS_DP<9>
  \dqs9_b_c||tdqs9_b_c\  = M_D_CPU1_SB_DQS_DN<9>
  VSS41  = GND
  CB0_B  = M_D_CPU1_SB_CB<0>
  VSS42  = GND
  CB1_B  = M_D_CPU1_SB_CB<1>
  VSS43  = GND
  DQ0_B  = M_D_CPU1_SB_DQ<0>
  VSS44  = GND
  DQ1_B  = M_D_CPU1_SB_DQ<1>
  VSS45  = GND
  DQS0_B_T  = M_D_CPU1_SB_DQS_DP<0>
  DQS0_B_C  = M_D_CPU1_SB_DQS_DN<0>
  VSS46  = GND
  DQ4_B  = M_D_CPU1_SB_DQ<4>
  VSS47  = GND
  DQ5_B  = M_D_CPU1_SB_DQ<5>
  VSS48  = GND
  DQ8_B  = M_D_CPU1_SB_DQ<8>
  VSS49  = GND
  DQ9_B  = M_D_CPU1_SB_DQ<9>
  VSS50  = GND
  DQS1_B_T  = M_D_CPU1_SB_DQS_DP<1>
  DQS1_B_C  = M_D_CPU1_SB_DQS_DN<1>
  VSS51  = GND
  DQ12_B  = M_D_CPU1_SB_DQ<12>
  VSS52  = GND
  DQ13_B  = M_D_CPU1_SB_DQ<13>
  VSS53  = GND
  DQ16_B  = M_D_CPU1_SB_DQ<16>
  VSS54  = GND
  DQ17_B  = M_D_CPU1_SB_DQ<17>
  VSS55  = GND
  DQS2_B_T  = M_D_CPU1_SB_DQS_DP<2>
  DQS2_B_C  = M_D_CPU1_SB_DQS_DN<2>
  VSS56  = GND
  DQ20_B  = M_D_CPU1_SB_DQ<20>
  VSS57  = GND
  DQ21_B  = M_D_CPU1_SB_DQ<21>
  VSS58  = GND
  DQ24_B  = M_D_CPU1_SB_DQ<24>
  VSS59  = GND
  DQ25_B  = M_D_CPU1_SB_DQ<25>
  VSS60  = GND
  DQS3_B_T  = M_D_CPU1_SB_DQS_DP<3>
  DQS3_B_C  = M_D_CPU1_SB_DQS_DN<3>
  VSS61  = GND
  DQ28_B  = M_D_CPU1_SB_DQ<28>
  VSS62  = GND
  DQ29_B  = M_D_CPU1_SB_DQ<29>
  VSS63  = GND
  RFU1  = TP_CHD_CPU1_DIMM1_FRU_1
  VIN_BULK1  = P12V_S3_AUX_CPU1_NVDIMM
  VIN_BULK2  = P12V_S3_AUX_CPU1_NVDIMM
  \pwr_good||fail_n\  = PWRGD_CHD_CPU1_DIMM1
  HSA  = PD_CHD_CPU1_DIMM1_SAA
  RFU2  = TP_CHD_CPU1_DIMM1_FRU_2
  RFU3  = TP_CHD_CPU1_DIMM1_FRU_3
  VSS64  = GND
  DQ2_A  = M_D_CPU1_SA_DQ<2>
  VSS65  = GND
  DQ3_A  = M_D_CPU1_SA_DQ<3>
  VSS66  = GND
  \dqs5_a_c||tdqs5_a_c||dqs5_a_t||tdqs5_a_t\  = M_D_CPU1_SA_DQS_DN<5>
  \dqs5_a_t||tdqs5_a_t\  = M_D_CPU1_SA_DQS_DP<5>
  VSS67  = GND
  DQ6_A  = M_D_CPU1_SA_DQ<6>
  VSS68  = GND
  DQ7_A  = M_D_CPU1_SA_DQ<7>
  VSS69  = GND
  DQ10_A  = M_D_CPU1_SA_DQ<10>
  VSS70  = GND
  DQ11_A  = M_D_CPU1_SA_DQ<11>
  VSS71  = GND
  \dqs6_a_c||tdqs6_a_c||dqs6_a_t||tdqs6_a_t\  = M_D_CPU1_SA_DQS_DN<6>
  \dqs6_a_t||tdqs6_a_t\  = M_D_CPU1_SA_DQS_DP<6>
  VSS72  = GND
  DQ14_A  = M_D_CPU1_SA_DQ<14>
  VSS73  = GND
  DQ15_A  = M_D_CPU1_SA_DQ<15>
  VSS74  = GND
  DQ18_A  = M_D_CPU1_SA_DQ<18>
  VSS75  = GND
  DQ19_A  = M_D_CPU1_SA_DQ<19>
  VSS76  = GND
  \dqs7_a_c||tdqs7_a_c\  = M_D_CPU1_SA_DQS_DN<7>
  \dqs7_a_t||tdqs7_a_t\  = M_D_CPU1_SA_DQS_DP<7>
  VSS77  = GND
  DQ22_A  = M_D_CPU1_SA_DQ<22>
  VSS78  = GND
  DQ23_A  = M_D_CPU1_SA_DQ<23>
  VSS79  = GND
  DQ26_A  = M_D_CPU1_SA_DQ<26>
  VSS80  = GND
  DQ27_A  = M_D_CPU1_SA_DQ<27>
  VSS81  = GND
  \dqs8_a_c||tdqs8_a_c\  = M_D_CPU1_SA_DQS_DN<8>
  \dqs8_a_t||tdqs8_a_t\  = M_D_CPU1_SA_DQS_DP<8>
  VSS82  = GND
  DQ30_A  = M_D_CPU1_SA_DQ<30>
  VSS83  = GND
  DQ31_A  = M_D_CPU1_SA_DQ<31>
  VSS84  = GND
  CB2_A  = M_D_CPU1_SA_CB<2>
  VSS85  = GND
  CB3_A  = M_D_CPU1_SA_CB<3>
  VSS86  = GND
  \dqs9_a_c||tdqs9_a_c\  = M_D_CPU1_SA_DQS_DN<9>
  \dqs9_a_t||tdqs9_a_t\  = M_D_CPU1_SA_DQS_DP<9>
  VSS87  = GND
  CB6_A  = M_D_CPU1_SA_CB<6>
  VSS88  = GND
  CB7_A  = M_D_CPU1_SA_CB<7>
  VSS89  = GND
  RESET_N  = RST_M_CD_CPU1_FPGA_N
  VSS90  = GND
  CS1_A_N  = M_D_CPU1_SA_CS_N<1>
  VSS91  = GND
  CA1_A  = M_D_CPU1_SA_CA<1>
  VSS92  = GND
  CA3_A  = M_D_CPU1_SA_CA<3>
  VSS93  = GND
  CA5_A  = M_D_CPU1_SA_CA<5>
  VSS94  = GND
  CK_T  = M_D_CPU1_CLK_DP<0>
  CK_C  = M_D_CPU1_CLK_DN<0>
  VSS95  = GND
  RFU4  = TP_CHD_CPU1_DIMM1_FRU_4
  CA1_B  = M_D_CPU1_SB_CA<1>
  VSS96  = GND
  CA3_B  = M_D_CPU1_SB_CA<3>
  VSS97  = GND
  CA5_B  = M_D_CPU1_SB_CA<5>
  VSS98  = GND
  PAR_B  = M_D_CPU1_SB_PAR
  VSS99  = GND
  CS1_B_N  = M_D_CPU1_SB_CS_N<1>
  VSS100  = GND
  RFU5  = TP_CHD_CPU1_DIMM1_FRU_5
  RFU6  = TP_CHD_CPU1_DIMM1_FRU_6
  VSS101  = GND
  CB6_B  = M_D_CPU1_SB_CB<6>
  VSS102  = GND
  CB7_B  = M_D_CPU1_SB_CB<7>
  VSS103  = GND
  DQS4_B_C  = M_D_CPU1_SB_DQS_DN<4>
  DQS4_B_T  = M_D_CPU1_SB_DQS_DP<4>
  VSS104  = GND
  CB2_B  = M_D_CPU1_SB_CB<2>
  VSS105  = GND
  CB3_B  = M_D_CPU1_SB_CB<3>
  VSS106  = GND
  DQ2_B  = M_D_CPU1_SB_DQ<2>
  VSS107  = GND
  DQ3_B  = M_D_CPU1_SB_DQ<3>
  VSS108  = GND
  \dqs5_b_c||tdqs5_b_c\  = M_D_CPU1_SB_DQS_DN<5>
  \dqs5_b_t||tdqs5_b_t\  = M_D_CPU1_SB_DQS_DP<5>
  VSS109  = GND
  DQ6_B  = M_D_CPU1_SB_DQ<6>
  VSS110  = GND
  DQ7_B  = M_D_CPU1_SB_DQ<7>
  VSS111  = GND
  DQ10_B  = M_D_CPU1_SB_DQ<10>
  VSS112  = GND
  DQ11_B  = M_D_CPU1_SB_DQ<11>
  VSS113  = GND
  \dqs6_b_c||tdqs6_b_c\  = M_D_CPU1_SB_DQS_DN<6>
  \dqs6_b_t||tdqs6_b_t\  = M_D_CPU1_SB_DQS_DP<6>
  VSS114  = GND
  DQ14_B  = M_D_CPU1_SB_DQ<14>
  VSS115  = GND
  DQ15_B  = M_D_CPU1_SB_DQ<15>
  VSS116  = GND
  DQ18_B  = M_D_CPU1_SB_DQ<18>
  VSS117  = GND
  DQ19_B  = M_D_CPU1_SB_DQ<19>
  VSS118  = GND
  \dqs7_b_c||tdqs7_b_c\  = M_D_CPU1_SB_DQS_DN<7>
  \dqs7_b_t||tdqs7_b_t\  = M_D_CPU1_SB_DQS_DP<7>
  VSS119  = GND
  DQ22_B  = M_D_CPU1_SB_DQ<22>
  VSS120  = GND
  DQ23_B  = M_D_CPU1_SB_DQ<23>
  VSS121  = GND
  DQ26_B  = M_D_CPU1_SB_DQ<26>
  VSS122  = GND
  DQ27_B  = M_D_CPU1_SB_DQ<27>
  VSS123  = GND
  \dqs8_b_c||tdqs8_b_c\  = M_D_CPU1_SB_DQS_DN<8>
  \dqs8_b_t||tdqs8_b_t\  = M_D_CPU1_SB_DQS_DP<8>
  VSS124  = GND
  DQ30_B  = M_D_CPU1_SB_DQ<30>
  VSS125  = GND
  DQ31_B  = M_D_CPU1_SB_DQ<31>
  VSS126  = GND
  G1  = GND
  G2  = GND
  G3  = GND

(kicad_pcb
	(version 20260206)
	(generator "pcbnew")
	(generator_version "10.0")
	(general
		(thickness 1.6)
		(legacy_teardrops no)
	)
	(paper "A4")
	(title_block
		(title "03242023_DA0F0TMBIJ0_F0T_Motherboard_J_brd_V01_OCP.brd")
		(comment 1 "Grand Teton / footprint 3586 of 6105 (J23), pads 1-45 of 291")
	)
	(layers
		(0 "F.Cu" signal "TOP")
		(4 "In1.Cu" signal "GND")
		(6 "In2.Cu" signal "IN1")
		(8 "In3.Cu" signal "GND1")
		(10 "In4.Cu" signal "IN2")
		(12 "In5.Cu" signal "GND2")
		(14 "In6.Cu" signal "IN3")
		(16 "In7.Cu" signal "GND3")
		(18 "In8.Cu" signal "VCC")
		(20 "In9.Cu" signal "VCC1")
		(22 "In10.Cu" signal "GND4")
		(24 "In11.Cu" signal "IN4")
		(26 "In12.Cu" signal "GND5")
		(28 "In13.Cu" signal "IN5")
		(30 "In14.Cu" signal "GND6")
		(32 "In15.Cu" signal "IN6")
		(34 "In16.Cu" signal "GND7")
		(2 "B.Cu" signal "BOTTOM")
		(9 "F.Adhes" user "F.Adhesive")
		(11 "B.Adhes" user "B.Adhesive")
		(13 "F.Paste" user "Package Geometry/Pastemask Top")
		(15 "B.Paste" user "Package Geometry/Pastemask Bottom")
		(5 "F.SilkS" user "Ref Des/Silkscreen Top")
		(7 "B.SilkS" user "Ref Des/Silkscreen Bottom")
		(1 "F.Mask" user "Board Geometry/Soldermask Top")
		(3 "B.Mask" user "Board Geometry/Soldermask Bottom")
		(17 "Dwgs.User" user "User.Drawings")
		(19 "Cmts.User" user "User.Comments")
		(21 "Eco1.User" user "User.Eco1")
		(23 "Eco2.User" user "User.Eco2")
		(25 "Edge.Cuts" user "Board Geometry/Outline")
		(27 "Margin" user)
		(31 "F.CrtYd" user "Package Geometry/Place Bound Top")
		(29 "B.CrtYd" user "Package Geometry/Place Bound Bottom")
		(35 "F.Fab" user "Ref Des/Assembly Top")
		(33 "B.Fab" user "Ref Des/Assembly Bottom")
	)
	(footprint ""
		(layer "F.Cu")
		(at 10.19048 -258.091686)
		(property "Reference" "J23"
			(at -5.69468 -80.480408 0)
			(unlocked yes)
			(layer "F.SilkS")
			(effects
				(font
					(size 0.7874 0.5842)
					(thickness 0.1524)
				)
				(justify left)
			)
		)
		(property "Value" ""
			(at 0 0 0)
			(layer "F.Fab")
			(effects
				(font
					(size 1.27 1.27)
				)
			)
		)
		(duplicate_pad_numbers_are_jumpers no)
		(pad "1" smd rect
			(at -2.050034 -63.324994 270)
			(size 0.519938 1.4986)
			(layers "F.Cu" "F.Mask" "F.Paste")
			(net "P12V_S3_AUX_CPU1_NVDIMM")
		)
		(pad "2" smd rect
			(at -2.050034 -62.47511 270)
			(size 0.519938 1.4986)
			(layers "F.Cu" "F.Mask" "F.Paste")
			(net "TP_CHD_CPU1_DIMM1_FRU_0")
		)
		(pad "3" smd rect
			(at -2.050034 -61.624972 270)
			(size 0.519938 1.4986)
			(layers "F.Cu" "F.Mask" "F.Paste")
			(net "P3V3_AUX")
		)
		(pad "4" smd rect
			(at -2.050034 -60.775088 270)
			(size 0.519938 1.4986)
			(layers "F.Cu" "F.Mask" "F.Paste")
			(net "I3C_SPD_DDRABCD_CPU1_LVC1_SCL_6")
		)
		(pad "5" smd rect
			(at -2.050034 -59.92495 270)
			(size 0.519938 1.4986)
			(layers "F.Cu" "F.Mask" "F.Paste")
			(net "I3C_SPD_DDRABCD_CPU1_LVC1_SDA")
		)
		(pad "6" smd rect
			(at -2.050034 -59.075066 270)
			(size 0.519938 1.4986)
			(layers "F.Cu" "F.Mask" "F.Paste")
			(net "GND")
		)
		(pad "7" smd rect
			(at -2.050034 -58.224928 270)
			(size 0.519938 1.4986)
			(layers "F.Cu" "F.Mask" "F.Paste")
			(net "M_D_CPU1_SA_DQ<0>")
		)
		(pad "8" smd rect
			(at -2.050034 -57.375044 270)
			(size 0.519938 1.4986)
			(layers "F.Cu" "F.Mask" "F.Paste")
			(net "GND")
		)
		(pad "9" smd rect
			(at -2.050034 -56.524906 270)
			(size 0.519938 1.4986)
			(layers "F.Cu" "F.Mask" "F.Paste")
			(net "M_D_CPU1_SA_DQ<1>")
		)
		(pad "10" smd rect
			(at -2.050034 -55.675022 270)
			(size 0.519938 1.4986)
			(layers "F.Cu" "F.Mask" "F.Paste")
			(net "GND")
		)
		(pad "11" smd rect
			(at -2.050034 -54.824884 270)
			(size 0.519938 1.4986)
			(layers "F.Cu" "F.Mask" "F.Paste")
			(net "M_D_CPU1_SA_DQS_DP<0>")
		)
		(pad "12" smd rect
			(at -2.050034 -53.975 270)
			(size 0.519938 1.4986)
			(layers "F.Cu" "F.Mask" "F.Paste")
			(net "M_D_CPU1_SA_DQS_DN<0>")
		)
		(pad "13" smd rect
			(at -2.050034 -53.125116 270)
			(size 0.519938 1.4986)
			(layers "F.Cu" "F.Mask" "F.Paste")
			(net "GND")
		)
		(pad "14" smd rect
			(at -2.050034 -52.274978 270)
			(size 0.519938 1.4986)
			(layers "F.Cu" "F.Mask" "F.Paste")
			(net "M_D_CPU1_SA_DQ<4>")
		)
		(pad "15" smd rect
			(at -2.050034 -51.425094 270)
			(size 0.519938 1.4986)
			(layers "F.Cu" "F.Mask" "F.Paste")
			(net "GND")
		)
		(pad "16" smd rect
			(at -2.050034 -50.574956 270)
			(size 0.519938 1.4986)
			(layers "F.Cu" "F.Mask" "F.Paste")
			(net "M_D_CPU1_SA_DQ<5>")
		)
		(pad "17" smd rect
			(at -2.050034 -49.725072 270)
			(size 0.519938 1.4986)
			(layers "F.Cu" "F.Mask" "F.Paste")
			(net "GND")
		)
		(pad "18" smd rect
			(at -2.050034 -48.874934 270)
			(size 0.519938 1.4986)
			(layers "F.Cu" "F.Mask" "F.Paste")
			(net "M_D_CPU1_SA_DQ<8>")
		)
		(pad "19" smd rect
			(at -2.050034 -48.02505 270)
			(size 0.519938 1.4986)
			(layers "F.Cu" "F.Mask" "F.Paste")
			(net "GND")
		)
		(pad "20" smd rect
			(at -2.050034 -47.174912 270)
			(size 0.519938 1.4986)
			(layers "F.Cu" "F.Mask" "F.Paste")
			(net "M_D_CPU1_SA_DQ<9>")
		)
		(pad "21" smd rect
			(at -2.050034 -46.325028 270)
			(size 0.519938 1.4986)
			(layers "F.Cu" "F.Mask" "F.Paste")
			(net "GND")
		)
		(pad "22" smd rect
			(at -2.050034 -45.47489 270)
			(size 0.519938 1.4986)
			(layers "F.Cu" "F.Mask" "F.Paste")
			(net "M_D_CPU1_SA_DQS_DP<1>")
		)
		(pad "23" smd rect
			(at -2.050034 -44.625006 270)
			(size 0.519938 1.4986)
			(layers "F.Cu" "F.Mask" "F.Paste")
			(net "M_D_CPU1_SA_DQS_DN<1>")
		)
		(pad "24" smd rect
			(at -2.050034 -43.775122 270)
			(size 0.519938 1.4986)
			(layers "F.Cu" "F.Mask" "F.Paste")
			(net "GND")
		)
		(pad "25" smd rect
			(at -2.050034 -42.924984 270)
			(size 0.519938 1.4986)
			(layers "F.Cu" "F.Mask" "F.Paste")
			(net "M_D_CPU1_SA_DQ<12>")
		)
		(pad "26" smd rect
			(at -2.050034 -42.0751 270)
			(size 0.519938 1.4986)
			(layers "F.Cu" "F.Mask" "F.Paste")
			(net "GND")
		)
		(pad "27" smd rect
			(at -2.050034 -41.224962 270)
			(size 0.519938 1.4986)
			(layers "F.Cu" "F.Mask" "F.Paste")
			(net "M_D_CPU1_SA_DQ<13>")
		)
		(pad "28" smd rect
			(at -2.050034 -40.375078 270)
			(size 0.519938 1.4986)
			(layers "F.Cu" "F.Mask" "F.Paste")
			(net "GND")
		)
		(pad "29" smd rect
			(at -2.050034 -39.52494 270)
			(size 0.519938 1.4986)
			(layers "F.Cu" "F.Mask" "F.Paste")
			(net "M_D_CPU1_SA_DQ<16>")
		)
		(pad "30" smd rect
			(at -2.050034 -38.675056 270)
			(size 0.519938 1.4986)
			(layers "F.Cu" "F.Mask" "F.Paste")
			(net "GND")
		)
		(pad "31" smd rect
			(at -2.050034 -37.824918 270)
			(size 0.519938 1.4986)
			(layers "F.Cu" "F.Mask" "F.Paste")
			(net "M_D_CPU1_SA_DQ<17>")
		)
		(pad "32" smd rect
			(at -2.050034 -36.975034 270)
			(size 0.519938 1.4986)
			(layers "F.Cu" "F.Mask" "F.Paste")
			(net "GND")
		)
		(pad "33" smd rect
			(at -2.050034 -36.124896 270)
			(size 0.519938 1.4986)
			(layers "F.Cu" "F.Mask" "F.Paste")
			(net "M_D_CPU1_SA_DQS_DP<2>")
		)
		(pad "34" smd rect
			(at -2.050034 -35.275012 270)
			(size 0.519938 1.4986)
			(layers "F.Cu" "F.Mask" "F.Paste")
			(net "M_D_CPU1_SA_DQS_DN<2>")
		)
		(pad "35" smd rect
			(at -2.050034 -34.425128 270)
			(size 0.519938 1.4986)
			(layers "F.Cu" "F.Mask" "F.Paste")
			(net "GND")
		)
		(pad "36" smd rect
			(at -2.050034 -33.57499 270)
			(size 0.519938 1.4986)
			(layers "F.Cu" "F.Mask" "F.Paste")
			(net "M_D_CPU1_SA_DQ<20>")
		)
		(pad "37" smd rect
			(at -2.050034 -32.725106 270)
			(size 0.519938 1.4986)
			(layers "F.Cu" "F.Mask" "F.Paste")
			(net "GND")
		)
		(pad "38" smd rect
			(at -2.050034 -31.874968 270)
			(size 0.519938 1.4986)
			(layers "F.Cu" "F.Mask" "F.Paste")
			(net "M_D_CPU1_SA_DQ<21>")
		)
		(pad "39" smd rect
			(at -2.050034 -31.025084 270)
			(size 0.519938 1.4986)
			(layers "F.Cu" "F.Mask" "F.Paste")
			(net "GND")
		)
		(pad "40" smd rect
			(at -2.050034 -30.174946 270)
			(size 0.519938 1.4986)
			(layers "F.Cu" "F.Mask" "F.Paste")
			(net "M_D_CPU1_SA_DQ<24>")
		)
		(pad "41" smd rect
			(at -2.050034 -29.325062 270)
			(size 0.519938 1.4986)
			(layers "F.Cu" "F.Mask" "F.Paste")
			(net "GND")
		)
		(pad "42" smd rect
			(at -2.050034 -28.474924 270)
			(size 0.519938 1.4986)
			(layers "F.Cu" "F.Mask" "F.Paste")
			(net "M_D_CPU1_SA_DQ<25>")
		)
		(pad "43" smd rect
			(at -2.050034 -27.62504 270)
			(size 0.519938 1.4986)
			(layers "F.Cu" "F.Mask" "F.Paste")
			(net "GND")
		)
		(pad "44" smd rect
			(at -2.050034 -26.774902 270)
			(size 0.519938 1.4986)
			(layers "F.Cu" "F.Mask" "F.Paste")
			(net "M_D_CPU1_SA_DQS_DP<3>")
		)
		(pad "45" smd rect
			(at -2.050034 -25.925018 270)
			(size 0.519938 1.4986)
			(layers "F.Cu" "F.Mask" "F.Paste")
			(net "M_D_CPU1_SA_DQS_DN<3>")
		)
	)
)
